# T6G (Grand Teton) — schematic netlist excerpt (pin names and nets, part order shuffled) for the footprints in the layout excerpt that follows; sources: Cadence DE-HDL packaged netlist, KiCad conversion of 04192023_DAF0TMB3IC0_F0TG_MB_C_brd_V02_OCP.brd

R1199  Q_RES  0 5% CHIP  pkg 0201LF  page 186 : A = RST_SMB_RT_ROM_R1_N ; B = FM_SMB_RT_ROM_MUX2_SEL
C764  Q_CAP_DIFFBUS  DIFF BUS_0.22UF 6.3V 20% X6S  pkg C0201  page 66 : \1\ = P5E_CPU1_P2_TX_C_DN<4> ; \2\ = P5E_CPU1_P2_TX_DN<4>
R655  Q_RES  1K 1% CHIP  pkg 0402LF  page 362 : A = P3V3_AUX ; B = P0V9_RETIMER_CPU0_INALERT

(kicad_pcb
	(version 20260206)
	(generator "pcbnew")
	(generator_version "10.0")
	(general
		(thickness 1.6)
		(legacy_teardrops no)
	)
	(paper "A4")
	(title_block
		(title "04192023_DAF0TMB3IC0_F0TG_MB_C_brd_V02_OCP.brd")
		(comment 1 "Grand Teton / footprints 1369-1371 of 8354")
	)
	(layers
		(0 "F.Cu" signal "TOP")
		(4 "In1.Cu" signal "GND")
		(6 "In2.Cu" signal "IN1")
		(8 "In3.Cu" signal "GND1")
		(10 "In4.Cu" signal "IN2")
		(12 "In5.Cu" signal "GND2")
		(14 "In6.Cu" signal "IN3")
		(16 "In7.Cu" signal "GND3")
		(18 "In8.Cu" signal "VCC")
		(20 "In9.Cu" signal "VCC1")
		(22 "In10.Cu" signal "GND4")
		(24 "In11.Cu" signal "IN4")
		(26 "In12.Cu" signal "GND5")
		(28 "In13.Cu" signal "IN5")
		(30 "In14.Cu" signal "GND6")
		(32 "In15.Cu" signal "IN6")
		(34 "In16.Cu" signal "GND7")
		(2 "B.Cu" signal "BOTTOM")
		(9 "F.Adhes" user "F.Adhesive")
		(11 "B.Adhes" user "B.Adhesive")
		(13 "F.Paste" user "Package Geometry/Pastemask Top")
		(15 "B.Paste" user "Package Geometry/Pastemask Bottom")
		(5 "F.SilkS" user "Ref Des/Silkscreen Top")
		(7 "B.SilkS" user "Ref Des/Silkscreen Bottom")
		(1 "F.Mask" user "Board Geometry/Soldermask Top")
		(3 "B.Mask" user "Board Geometry/Soldermask Bottom")
		(17 "Dwgs.User" user "User.Drawings")
		(19 "Cmts.User" user "User.Comments")
		(21 "Eco1.User" user "User.Eco1")
		(23 "Eco2.User" user "User.Eco2")
		(25 "Edge.Cuts" user "Board Geometry/Outline")
		(27 "Margin" user)
		(31 "F.CrtYd" user "Package Geometry/Place Bound Top")
		(29 "B.CrtYd" user "Package Geometry/Place Bound Bottom")
		(35 "F.Fab" user "Ref Des/Assembly Top")
		(33 "B.Fab" user "Ref Des/Assembly Bottom")
	)
	(footprint ""
		(layer "F.Cu")
		(at 148.637244 -375.49963 -90)
		(property "Reference" "C764"
			(at 0 0 270)
			(layer "F.SilkS")
			(hide yes)
			(effects
				(font
					(size 1.27 1.27)
				)
			)
		)
		(property "Value" ""
			(at 0 0 270)
			(layer "F.Fab")
			(effects
				(font
					(size 1.27 1.27)
				)
			)
		)
		(duplicate_pad_numbers_are_jumpers no)
		(fp_line
			(start -0.299974 0.150114)
			(end -0.299974 -0.150114)
			(stroke
				(width 0.1)
				(type default)
			)
			(layer "F.Fab")
		)
		(fp_line
			(start 0.299974 0.150114)
			(end -0.299974 0.150114)
			(stroke
				(width 0.1)
				(type default)
			)
			(layer "F.Fab")
		)
		(fp_line
			(start -0.299974 -0.150114)
			(end 0.299974 -0.150114)
			(stroke
				(width 0.1)
				(type default)
			)
			(layer "F.Fab")
		)
		(fp_line
			(start 0.299974 -0.150114)
			(end 0.299974 0.150114)
			(stroke
				(width 0.1)
				(type default)
			)
			(layer "F.Fab")
		)
		(pad "1" smd rect
			(at -0.2667 0 270)
			(size 0.3048 0.381)
			(layers "F.Cu" "F.Mask" "F.Paste")
			(net "P5E_CPU1_P2_TX_C_DN<4>")
		)
		(pad "2" smd rect
			(at 0.2667 0 270)
			(size 0.3048 0.381)
			(layers "F.Cu" "F.Mask" "F.Paste")
			(net "P5E_CPU1_P2_TX_DN<4>")
		)
	)
	(footprint ""
		(layer "F.Cu")
		(at 113.440718 -401.280122)
		(property "Reference" "R1199"
			(at 0 0 0)
			(layer "F.SilkS")
			(hide yes)
			(effects
				(font
					(size 1.27 1.27)
				)
			)
		)
		(property "Value" ""
			(at 0 0 0)
			(layer "F.Fab")
			(effects
				(font
					(size 1.27 1.27)
				)
			)
		)
		(duplicate_pad_numbers_are_jumpers no)
		(fp_line
			(start -0.32512 -0.175006)
			(end 0.32512 -0.175006)
			(stroke
				(width 0.1)
				(type default)
			)
			(layer "F.Fab")
		)
		(fp_line
			(start -0.32512 0.175006)
			(end -0.32512 -0.175006)
			(stroke
				(width 0.1)
				(type default)
			)
			(layer "F.Fab")
		)
		(fp_line
			(start 0.32512 -0.175006)
			(end 0.32512 0.175006)
			(stroke
				(width 0.1)
				(type default)
			)
			(layer "F.Fab")
		)
		(fp_line
			(start 0.32512 0.175006)
			(end -0.32512 0.175006)
			(stroke
				(width 0.1)
				(type default)
			)
			(layer "F.Fab")
		)
		(pad "1" smd rect
			(at -0.2667 0)
			(size 0.3048 0.381)
			(layers "F.Cu" "F.Mask" "F.Paste")
			(net "RST_SMB_RT_ROM_R1_N")
		)
		(pad "2" smd rect
			(at 0.2667 0 180)
			(size 0.3048 0.381)
			(layers "F.Cu" "F.Mask" "F.Paste")
			(net "FM_SMB_RT_ROM_MUX2_SEL")
		)
	)
	(footprint ""
		(layer "F.Cu")
		(at 439.029602 -424.80611)
		(property "Reference" "R655"
			(at 0 0 0)
			(layer "F.SilkS")
			(hide yes)
			(effects
				(font
					(size 1.27 1.27)
				)
			)
		)
		(property "Value" ""
			(at 0 0 0)
			(layer "F.Fab")
			(effects
				(font
					(size 1.27 1.27)
				)
			)
		)
		(duplicate_pad_numbers_are_jumpers no)
		(fp_line
			(start -0.7874 -0.4064)
			(end 0.7874 -0.4064)
			(stroke
				(width 0.1524)
				(type default)
			)
			(layer "F.SilkS")
		)
		(fp_line
			(start -0.7874 0.4064)
			(end -0.7874 -0.4064)
			(stroke
				(width 0.1524)
				(type default)
			)
			(layer "F.SilkS")
		)
		(fp_line
			(start 0.7874 -0.4064)
			(end 0.7874 0.4064)
			(stroke
				(width 0.1524)
				(type default)
			)
			(layer "F.SilkS")
		)
		(fp_line
			(start 0.7874 0.4064)
			(end -0.7874 0.4064)
			(stroke
				(width 0.1524)
				(type default)
			)
			(layer "F.SilkS")
		)
		(fp_line
			(start -0.67945 -0.305054)
			(end -0.12065 -0.305054)
			(stroke
				(width 0.1)
				(type default)
			)
			(layer "F.Fab")
		)
		(fp_line
			(start -0.67945 0.3048)
			(end -0.67945 -0.305054)
			(stroke
				(width 0.1)
				(type default)
			)
			(layer "F.Fab")
		)
		(fp_line
			(start -0.12065 -0.305054)
			(end -0.12065 -0.2794)
			(stroke
				(width 0.1)
				(type default)
			)
			(layer "F.Fab")
		)
		(fp_line
			(start -0.12065 -0.2794)
			(end 0.12065 -0.2794)
			(stroke
				(width 0.1)
				(type default)
			)
			(layer "F.Fab")
		)
		(fp_line
			(start -0.12065 0.2794)
			(end -0.12065 0.3048)
			(stroke
				(width 0.1)
				(type default)
			)
			(layer "F.Fab")
		)
		(fp_line
			(start -0.12065 0.3048)
			(end -0.67945 0.3048)
			(stroke
				(width 0.1)
				(type default)
			)
			(layer "F.Fab")
		)
		(fp_line
			(start 0.120396 0.2794)
			(end -0.12065 0.2794)
			(stroke
				(width 0.1)
				(type default)
			)
			(layer "F.Fab")
		)
		(fp_line
			(start 0.120396 0.3048)
			(end 0.120396 0.2794)
			(stroke
				(width 0.1)
				(type default)
			)
			(layer "F.Fab")
		)
		(fp_line
			(start 0.12065 -0.3048)
			(end 0.67945 -0.3048)
			(stroke
				(width 0.1)
				(type default)
			)
			(layer "F.Fab")
		)
		(fp_line
			(start 0.12065 -0.2794)
			(end 0.12065 -0.3048)
			(stroke
				(width 0.1)
				(type default)
			)
			(layer "F.Fab")
		)
		(fp_line
			(start 0.67945 -0.3048)
			(end 0.67945 0.3048)
			(stroke
				(width 0.1)
				(type default)
			)
			(layer "F.Fab")
		)
		(fp_line
			(start 0.67945 0.3048)
			(end 0.120396 0.3048)
			(stroke
				(width 0.1)
				(type default)
			)
			(layer "F.Fab")
		)
		(pad "1" smd circle
			(at -0.40005 0)
			(size 0 0)
			(layers "F.Cu" "F.Mask" "F.Paste")
			(net "P3V3_AUX")
		)
		(pad "2" smd circle
			(at 0.40005 0)
			(size 0 0)
			(layers "F.Cu" "F.Mask" "F.Paste")
			(net "P0V9_RETIMER_CPU0_INALERT")
		)
	)
)
